(kicad_pcb
	(version 20260206)
	(generator "pcbnew")
	(generator_version "10.0")
	(general
		(thickness 1.6)
		(legacy_teardrops no)
	)
	(paper "A4")
	(title_block
		(title "01162023_DA0F0TEBIF0_F0T_Expander_BD_F_brd_V02_OCP.brd")
		(comment 1 "Grand Teton / footprints 5774-5780 of 9728")
	)
	(layers
		(0 "F.Cu" signal "TOP")
		(4 "In1.Cu" signal "GND")
		(6 "In2.Cu" signal "VCC")
		(8 "In3.Cu" signal "VCC1")
		(10 "In4.Cu" signal "GND1")
		(12 "In5.Cu" signal "IN1")
		(14 "In6.Cu" signal "GND2")
		(16 "In7.Cu" signal "IN2")
		(18 "In8.Cu" signal "GND3")
		(20 "In9.Cu" signal "IN3")
		(22 "In10.Cu" signal "GND4")
		(24 "In11.Cu" signal "IN4")
		(26 "In12.Cu" signal "GND5")
		(28 "In13.Cu" signal "IN5")
		(30 "In14.Cu" signal "GND6")
		(32 "In15.Cu" signal "IN6")
		(34 "In16.Cu" signal "GND7")
		(2 "B.Cu" signal "BOTTOM")
		(9 "F.Adhes" user "F.Adhesive")
		(11 "B.Adhes" user "B.Adhesive")
		(13 "F.Paste" user "Package Geometry/Pastemask Top")
		(15 "B.Paste" user "Package Geometry/Pastemask Bottom")
		(5 "F.SilkS" user "Ref Des/Silkscreen Top")
		(7 "B.SilkS" user "Ref Des/Silkscreen Bottom")
		(1 "F.Mask" user "Board Geometry/Soldermask Top")
		(3 "B.Mask" user "Board Geometry/Soldermask Bottom")
		(17 "Dwgs.User" user "User.Drawings")
		(19 "Cmts.User" user "User.Comments")
		(21 "Eco1.User" user "User.Eco1")
		(23 "Eco2.User" user "User.Eco2")
		(25 "Edge.Cuts" user "Board Geometry/Outline")
		(27 "Margin" user)
		(31 "F.CrtYd" user "Package Geometry/Place Bound Top")
		(29 "B.CrtYd" user "Package Geometry/Place Bound Bottom")
		(35 "F.Fab" user "Ref Des/Assembly Top")
		(33 "B.Fab" user "Ref Des/Assembly Bottom")
	)
	(footprint ""
		(layer "F.Cu")
		(at 376.34926 -300.197012 -90)
		(property "Reference" "C3540"
			(at 0 0 270)
			(layer "F.SilkS")
			(hide yes)
			(effects
				(font
					(size 1.27 1.27)
				)
			)
		)
		(property "Value" ""
			(at 0 0 270)
			(layer "F.Fab")
			(effects
				(font
					(size 1.27 1.27)
				)
			)
		)
		(duplicate_pad_numbers_are_jumpers no)
		(fp_line
			(start -0.299974 0.150114)
			(end -0.299974 -0.150114)
			(stroke
				(width 0.1)
				(type default)
			)
			(layer "F.Fab")
		)
		(fp_line
			(start 0.299974 0.150114)
			(end -0.299974 0.150114)
			(stroke
				(width 0.1)
				(type default)
			)
			(layer "F.Fab")
		)
		(fp_line
			(start -0.299974 -0.150114)
			(end 0.299974 -0.150114)
			(stroke
				(width 0.1)
				(type default)
			)
			(layer "F.Fab")
		)
		(fp_line
			(start 0.299974 -0.150114)
			(end 0.299974 0.150114)
			(stroke
				(width 0.1)
				(type default)
			)
			(layer "F.Fab")
		)
		(pad "1" smd rect
			(at -0.2667 0 270)
			(size 0.3048 0.381)
			(layers "F.Cu" "F.Mask" "F.Paste")
			(net "P1V8_PLL0_PEX3")
		)
		(pad "2" smd rect
			(at 0.2667 0 270)
			(size 0.3048 0.381)
			(layers "F.Cu" "F.Mask" "F.Paste")
			(net "GND")
		)
	)
	(footprint ""
		(layer "F.Cu")
		(at 266.956032 -115.590574 90)
		(property "Reference" "U29"
			(at 2.568956 -0.256032 0)
			(unlocked yes)
			(layer "F.SilkS")
			(effects
				(font
					(size 0.7874 0.5842)
					(thickness 0.1524)
				)
			)
		)
		(property "Value" ""
			(at 0 0 90)
			(layer "F.Fab")
			(effects
				(font
					(size 1.27 1.27)
				)
			)
		)
		(duplicate_pad_numbers_are_jumpers no)
		(fp_line
			(start -1.949958 -1.610106)
			(end 1.949958 -1.610106)
			(stroke
				(width 0.1524)
				(type default)
			)
			(layer "F.SilkS")
		)
		(fp_line
			(start 1.949958 -1.560068)
			(end 1.949958 1.610106)
			(stroke
				(width 0.1524)
				(type default)
			)
			(layer "F.SilkS")
		)
		(fp_line
			(start 1.949958 1.610106)
			(end -1.949958 1.610106)
			(stroke
				(width 0.1524)
				(type default)
			)
			(layer "F.SilkS")
		)
		(fp_line
			(start -1.949958 1.610106)
			(end -1.949958 -1.610106)
			(stroke
				(width 0.1524)
				(type default)
			)
			(layer "F.SilkS")
		)
		(fp_line
			(start 0.750062 -1.560068)
			(end 0.750062 1.560068)
			(stroke
				(width 0.1)
				(type default)
			)
			(layer "F.Fab")
		)
		(fp_line
			(start -0.750062 -1.560068)
			(end 0.750062 -1.560068)
			(stroke
				(width 0.1)
				(type default)
			)
			(layer "F.Fab")
		)
		(fp_line
			(start 0.750062 1.560068)
			(end -0.750062 1.560068)
			(stroke
				(width 0.1)
				(type default)
			)
			(layer "F.Fab")
		)
		(fp_line
			(start -0.750062 1.560068)
			(end -0.750062 -1.560068)
			(stroke
				(width 0.1)
				(type default)
			)
			(layer "F.Fab")
		)
		(pad "D" smd rect
			(at 1.100074 0)
			(size 1.016 1.4224)
			(layers "F.Cu" "F.Mask" "F.Paste")
			(net "HP_NIC4_EN")
		)
		(pad "G" smd rect
			(at -1.100074 -0.94996)
			(size 1.016 1.4224)
			(layers "F.Cu" "F.Mask" "F.Paste")
			(net "PRSNT_NIC4_R_N")
		)
		(pad "S" smd rect
			(at -1.100074 0.94996)
			(size 1.016 1.4224)
			(layers "F.Cu" "F.Mask" "F.Paste")
			(net "GND")
		)
	)
	(footprint ""
		(layer "F.Cu")
		(at 363.474 -196.723 180)
		(property "Reference" "R4675"
			(at 0 0 180)
			(layer "F.SilkS")
			(hide yes)
			(effects
				(font
					(size 1.27 1.27)
				)
			)
		)
		(property "Value" ""
			(at 0 0 180)
			(layer "F.Fab")
			(effects
				(font
					(size 1.27 1.27)
				)
			)
		)
		(duplicate_pad_numbers_are_jumpers no)
		(fp_line
			(start 0.7874 0.4064)
			(end -0.7874 0.4064)
			(stroke
				(width 0.1524)
				(type default)
			)
			(layer "F.SilkS")
		)
		(fp_line
			(start 0.7874 -0.4064)
			(end 0.7874 0.4064)
			(stroke
				(width 0.1524)
				(type default)
			)
			(layer "F.SilkS")
		)
		(fp_line
			(start -0.7874 0.4064)
			(end -0.7874 -0.4064)
			(stroke
				(width 0.1524)
				(type default)
			)
			(layer "F.SilkS")
		)
		(fp_line
			(start -0.7874 -0.4064)
			(end 0.7874 -0.4064)
			(stroke
				(width 0.1524)
				(type default)
			)
			(layer "F.SilkS")
		)
		(fp_line
			(start 0.67945 0.3048)
			(end 0.120396 0.3048)
			(stroke
				(width 0.1)
				(type default)
			)
			(layer "F.Fab")
		)
		(fp_line
			(start 0.67945 -0.3048)
			(end 0.67945 0.3048)
			(stroke
				(width 0.1)
				(type default)
			)
			(layer "F.Fab")
		)
		(fp_line
			(start 0.12065 -0.2794)
			(end 0.12065 -0.3048)
			(stroke
				(width 0.1)
				(type default)
			)
			(layer "F.Fab")
		)
		(fp_line
			(start 0.12065 -0.3048)
			(end 0.67945 -0.3048)
			(stroke
				(width 0.1)
				(type default)
			)
			(layer "F.Fab")
		)
		(fp_line
			(start 0.120396 0.3048)
			(end 0.120396 0.2794)
			(stroke
				(width 0.1)
				(type default)
			)
			(layer "F.Fab")
		)
		(fp_line
			(start 0.120396 0.2794)
			(end -0.12065 0.2794)
			(stroke
				(width 0.1)
				(type default)
			)
			(layer "F.Fab")
		)
		(fp_line
			(start -0.12065 0.3048)
			(end -0.67945 0.3048)
			(stroke
				(width 0.1)
				(type default)
			)
			(layer "F.Fab")
		)
		(fp_line
			(start -0.12065 0.2794)
			(end -0.12065 0.3048)
			(stroke
				(width 0.1)
				(type default)
			)
			(layer "F.Fab")
		)
		(fp_line
			(start -0.12065 -0.2794)
			(end 0.12065 -0.2794)
			(stroke
				(width 0.1)
				(type default)
			)
			(layer "F.Fab")
		)
		(fp_line
			(start -0.12065 -0.305054)
			(end -0.12065 -0.2794)
			(stroke
				(width 0.1)
				(type default)
			)
			(layer "F.Fab")
		)
		(fp_line
			(start -0.67945 0.3048)
			(end -0.67945 -0.305054)
			(stroke
				(width 0.1)
				(type default)
			)
			(layer "F.Fab")
		)
		(fp_line
			(start -0.67945 -0.305054)
			(end -0.12065 -0.305054)
			(stroke
				(width 0.1)
				(type default)
			)
			(layer "F.Fab")
		)
		(pad "1" smd circle
			(at -0.40005 0 180)
			(size 0 0)
			(layers "F.Cu" "F.Mask" "F.Paste")
			(net "SSD5_PEX_PWR_EN_R")
		)
		(pad "2" smd circle
			(at 0.40005 0 180)
			(size 0 0)
			(layers "F.Cu" "F.Mask" "F.Paste")
			(net "GND")
		)
	)
	(footprint ""
		(layer "F.Cu")
		(at 319.70599 -386.958332 180)
		(property "Reference" "C4116"
			(at 0 0 180)
			(layer "F.SilkS")
			(hide yes)
			(effects
				(font
					(size 1.27 1.27)
				)
			)
		)
		(property "Value" ""
			(at 0 0 180)
			(layer "F.Fab")
			(effects
				(font
					(size 1.27 1.27)
				)
			)
		)
		(duplicate_pad_numbers_are_jumpers no)
		(fp_line
			(start 0.7874 0.4064)
			(end -0.7874 0.4064)
			(stroke
				(width 0.1524)
				(type default)
			)
			(layer "F.SilkS")
		)
		(fp_line
			(start 0.7874 -0.4064)
			(end 0.7874 0.4064)
			(stroke
				(width 0.1524)
				(type default)
			)
			(layer "F.SilkS")
		)
		(fp_line
			(start -0.7874 0.4064)
			(end -0.7874 -0.4064)
			(stroke
				(width 0.1524)
				(type default)
			)
			(layer "F.SilkS")
		)
		(fp_line
			(start -0.7874 -0.4064)
			(end 0.7874 -0.4064)
			(stroke
				(width 0.1524)
				(type default)
			)
			(layer "F.SilkS")
		)
		(fp_line
			(start 0.67945 0.3048)
			(end 0.120396 0.3048)
			(stroke
				(width 0.1)
				(type default)
			)
			(layer "F.Fab")
		)
		(fp_line
			(start 0.67945 -0.3048)
			(end 0.67945 0.3048)
			(stroke
				(width 0.1)
				(type default)
			)
			(layer "F.Fab")
		)
		(fp_line
			(start 0.12065 -0.2794)
			(end 0.12065 -0.3048)
			(stroke
				(width 0.1)
				(type default)
			)
			(layer "F.Fab")
		)
		(fp_line
			(start 0.12065 -0.3048)
			(end 0.67945 -0.3048)
			(stroke
				(width 0.1)
				(type default)
			)
			(layer "F.Fab")
		)
		(fp_line
			(start 0.120396 0.3048)
			(end 0.120396 0.2794)
			(stroke
				(width 0.1)
				(type default)
			)
			(layer "F.Fab")
		)
		(fp_line
			(start 0.120396 0.2794)
			(end -0.12065 0.2794)
			(stroke
				(width 0.1)
				(type default)
			)
			(layer "F.Fab")
		)
		(fp_line
			(start -0.12065 0.3048)
			(end -0.67945 0.3048)
			(stroke
				(width 0.1)
				(type default)
			)
			(layer "F.Fab")
		)
		(fp_line
			(start -0.12065 0.2794)
			(end -0.12065 0.3048)
			(stroke
				(width 0.1)
				(type default)
			)
			(layer "F.Fab")
		)
		(fp_line
			(start -0.12065 -0.2794)
			(end 0.12065 -0.2794)
			(stroke
				(width 0.1)
				(type default)
			)
			(layer "F.Fab")
		)
		(fp_line
			(start -0.12065 -0.305054)
			(end -0.12065 -0.2794)
			(stroke
				(width 0.1)
				(type default)
			)
			(layer "F.Fab")
		)
		(fp_line
			(start -0.67945 0.3048)
			(end -0.67945 -0.305054)
			(stroke
				(width 0.1)
				(type default)
			)
			(layer "F.Fab")
		)
		(fp_line
			(start -0.67945 -0.305054)
			(end -0.12065 -0.305054)
			(stroke
				(width 0.1)
				(type default)
			)
			(layer "F.Fab")
		)
		(pad "1" smd circle
			(at -0.40005 0 180)
			(size 0 0)
			(layers "F.Cu" "F.Mask" "F.Paste")
			(net "GND")
		)
		(pad "2" smd circle
			(at 0.40005 0 180)
			(size 0 0)
			(layers "F.Cu" "F.Mask" "F.Paste")
			(net "GPU_FPGA_OVERT_N")
		)
	)
	(footprint ""
		(layer "F.Cu")
		(at 1.729994 -255.046734 -90)
		(property "Reference" "R6469"
			(at 0 0 270)
			(layer "F.SilkS")
			(hide yes)
			(effects
				(font
					(size 1.27 1.27)
				)
			)
		)
		(property "Value" ""
			(at 0 0 270)
			(layer "F.Fab")
			(effects
				(font
					(size 1.27 1.27)
				)
			)
		)
		(duplicate_pad_numbers_are_jumpers no)
		(fp_line
			(start -0.7874 0.4064)
			(end -0.7874 -0.4064)
			(stroke
				(width 0.1524)
				(type default)
			)
			(layer "F.SilkS")
		)
		(fp_line
			(start 0.7874 0.4064)
			(end -0.7874 0.4064)
			(stroke
				(width 0.1524)
				(type default)
			)
			(layer "F.SilkS")
		)
		(fp_line
			(start -0.7874 -0.4064)
			(end 0.7874 -0.4064)
			(stroke
				(width 0.1524)
				(type default)
			)
			(layer "F.SilkS")
		)
		(fp_line
			(start 0.7874 -0.4064)
			(end 0.7874 0.4064)
			(stroke
				(width 0.1524)
				(type default)
			)
			(layer "F.SilkS")
		)
		(fp_line
			(start -0.67945 0.3048)
			(end -0.67945 -0.305054)
			(stroke
				(width 0.1)
				(type default)
			)
			(layer "F.Fab")
		)
		(fp_line
			(start -0.12065 0.3048)
			(end -0.67945 0.3048)
			(stroke
				(width 0.1)
				(type default)
			)
			(layer "F.Fab")
		)
		(fp_line
			(start 0.120396 0.3048)
			(end 0.120396 0.2794)
			(stroke
				(width 0.1)
				(type default)
			)
			(layer "F.Fab")
		)
		(fp_line
			(start 0.67945 0.3048)
			(end 0.120396 0.3048)
			(stroke
				(width 0.1)
				(type default)
			)
			(layer "F.Fab")
		)
		(fp_line
			(start -0.12065 0.2794)
			(end -0.12065 0.3048)
			(stroke
				(width 0.1)
				(type default)
			)
			(layer "F.Fab")
		)
		(fp_line
			(start 0.120396 0.2794)
			(end -0.12065 0.2794)
			(stroke
				(width 0.1)
				(type default)
			)
			(layer "F.Fab")
		)
		(fp_line
			(start -0.12065 -0.2794)
			(end 0.12065 -0.2794)
			(stroke
				(width 0.1)
				(type default)
			)
			(layer "F.Fab")
		)
		(fp_line
			(start 0.12065 -0.2794)
			(end 0.12065 -0.3048)
			(stroke
				(width 0.1)
				(type default)
			)
			(layer "F.Fab")
		)
		(fp_line
			(start 0.12065 -0.3048)
			(end 0.67945 -0.3048)
			(stroke
				(width 0.1)
				(type default)
			)
			(layer "F.Fab")
		)
		(fp_line
			(start 0.67945 -0.3048)
			(end 0.67945 0.3048)
			(stroke
				(width 0.1)
				(type default)
			)
			(layer "F.Fab")
		)
		(fp_line
			(start -0.67945 -0.305054)
			(end -0.12065 -0.305054)
			(stroke
				(width 0.1)
				(type default)
			)
			(layer "F.Fab")
		)
		(fp_line
			(start -0.12065 -0.305054)
			(end -0.12065 -0.2794)
			(stroke
				(width 0.1)
				(type default)
			)
			(layer "F.Fab")
		)
		(pad "1" smd circle
			(at -0.40005 0 270)
			(size 0 0)
			(layers "F.Cu" "F.Mask" "F.Paste")
			(net "P1V25_SERDES_VDDPLL_PEX0")
		)
		(pad "2" smd circle
			(at 0.40005 0 270)
			(size 0 0)
			(layers "F.Cu" "F.Mask" "F.Paste")
			(net "P1V25_SERDES_VDDPLL_PEX0_C6")
		)
	)
	(footprint ""
		(layer "F.Cu")
		(at 446.814448 -66.32194 90)
		(property "Reference" "R6021"
			(at 0 0 90)
			(layer "F.SilkS")
			(hide yes)
			(effects
				(font
					(size 1.27 1.27)
				)
			)
		)
		(property "Value" ""
			(at 0 0 90)
			(layer "F.Fab")
			(effects
				(font
					(size 1.27 1.27)
				)
			)
		)
		(duplicate_pad_numbers_are_jumpers no)
		(fp_line
			(start 0.7874 -0.4064)
			(end 0.7874 0.4064)
			(stroke
				(width 0.1524)
				(type default)
			)
			(layer "F.SilkS")
		)
		(fp_line
			(start -0.7874 -0.4064)
			(end 0.7874 -0.4064)
			(stroke
				(width 0.1524)
				(type default)
			)
			(layer "F.SilkS")
		)
		(fp_line
			(start 0.7874 0.4064)
			(end -0.7874 0.4064)
			(stroke
				(width 0.1524)
				(type default)
			)
			(layer "F.SilkS")
		)
		(fp_line
			(start -0.7874 0.4064)
			(end -0.7874 -0.4064)
			(stroke
				(width 0.1524)
				(type default)
			)
			(layer "F.SilkS")
		)
		(fp_line
			(start -0.12065 -0.305054)
			(end -0.12065 -0.2794)
			(stroke
				(width 0.1)
				(type default)
			)
			(layer "F.Fab")
		)
		(fp_line
			(start -0.67945 -0.305054)
			(end -0.12065 -0.305054)
			(stroke
				(width 0.1)
				(type default)
			)
			(layer "F.Fab")
		)
		(fp_line
			(start 0.67945 -0.3048)
			(end 0.67945 0.3048)
			(stroke
				(width 0.1)
				(type default)
			)
			(layer "F.Fab")
		)
		(fp_line
			(start 0.12065 -0.3048)
			(end 0.67945 -0.3048)
			(stroke
				(width 0.1)
				(type default)
			)
			(layer "F.Fab")
		)
		(fp_line
			(start 0.12065 -0.2794)
			(end 0.12065 -0.3048)
			(stroke
				(width 0.1)
				(type default)
			)
			(layer "F.Fab")
		)
		(fp_line
			(start -0.12065 -0.2794)
			(end 0.12065 -0.2794)
			(stroke
				(width 0.1)
				(type default)
			)
			(layer "F.Fab")
		)
		(fp_line
			(start 0.120396 0.2794)
			(end -0.12065 0.2794)
			(stroke
				(width 0.1)
				(type default)
			)
			(layer "F.Fab")
		)
		(fp_line
			(start -0.12065 0.2794)
			(end -0.12065 0.3048)
			(stroke
				(width 0.1)
				(type default)
			)
			(layer "F.Fab")
		)
		(fp_line
			(start 0.67945 0.3048)
			(end 0.120396 0.3048)
			(stroke
				(width 0.1)
				(type default)
			)
			(layer "F.Fab")
		)
		(fp_line
			(start 0.120396 0.3048)
			(end 0.120396 0.2794)
			(stroke
				(width 0.1)
				(type default)
			)
			(layer "F.Fab")
		)
		(fp_line
			(start -0.12065 0.3048)
			(end -0.67945 0.3048)
			(stroke
				(width 0.1)
				(type default)
			)
			(layer "F.Fab")
		)
		(fp_line
			(start -0.67945 0.3048)
			(end -0.67945 -0.305054)
			(stroke
				(width 0.1)
				(type default)
			)
			(layer "F.Fab")
		)
		(pad "1" smd circle
			(at -0.40005 0 90)
			(size 0 0)
			(layers "F.Cu" "F.Mask" "F.Paste")
			(net "SSD15_PWR_EN_R")
		)
		(pad "2" smd circle
			(at 0.40005 0 90)
			(size 0 0)
			(layers "F.Cu" "F.Mask" "F.Paste")
			(net "P12V_SSD15_CO_EN")
		)
	)
	(footprint ""
		(layer "F.Cu")
		(at 352.1837 -61.487812 180)
		(property "Reference" "R6014"
			(at 0 0 180)
			(layer "F.SilkS")
			(hide yes)
			(effects
				(font
					(size 1.27 1.27)
				)
			)
		)
		(property "Value" ""
			(at 0 0 180)
			(layer "F.Fab")
			(effects
				(font
					(size 1.27 1.27)
				)
			)
		)
		(duplicate_pad_numbers_are_jumpers no)
		(fp_line
			(start 0.7874 0.4064)
			(end -0.7874 0.4064)
			(stroke
				(width 0.1524)
				(type default)
			)
			(layer "F.SilkS")
		)
		(fp_line
			(start 0.7874 -0.4064)
			(end 0.7874 0.4064)
			(stroke
				(width 0.1524)
				(type default)
			)
			(layer "F.SilkS")
		)
		(fp_line
			(start -0.7874 0.4064)
			(end -0.7874 -0.4064)
			(stroke
				(width 0.1524)
				(type default)
			)
			(layer "F.SilkS")
		)
		(fp_line
			(start -0.7874 -0.4064)
			(end 0.7874 -0.4064)
			(stroke
				(width 0.1524)
				(type default)
			)
			(layer "F.SilkS")
		)
		(fp_line
			(start 0.67945 0.3048)
			(end 0.120396 0.3048)
			(stroke
				(width 0.1)
				(type default)
			)
			(layer "F.Fab")
		)
		(fp_line
			(start 0.67945 -0.3048)
			(end 0.67945 0.3048)
			(stroke
				(width 0.1)
				(type default)
			)
			(layer "F.Fab")
		)
		(fp_line
			(start 0.12065 -0.2794)
			(end 0.12065 -0.3048)
			(stroke
				(width 0.1)
				(type default)
			)
			(layer "F.Fab")
		)
		(fp_line
			(start 0.12065 -0.3048)
			(end 0.67945 -0.3048)
			(stroke
				(width 0.1)
				(type default)
			)
			(layer "F.Fab")
		)
		(fp_line
			(start 0.120396 0.3048)
			(end 0.120396 0.2794)
			(stroke
				(width 0.1)
				(type default)
			)
			(layer "F.Fab")
		)
		(fp_line
			(start 0.120396 0.2794)
			(end -0.12065 0.2794)
			(stroke
				(width 0.1)
				(type default)
			)
			(layer "F.Fab")
		)
		(fp_line
			(start -0.12065 0.3048)
			(end -0.67945 0.3048)
			(stroke
				(width 0.1)
				(type default)
			)
			(layer "F.Fab")
		)
		(fp_line
			(start -0.12065 0.2794)
			(end -0.12065 0.3048)
			(stroke
				(width 0.1)
				(type default)
			)
			(layer "F.Fab")
		)
		(fp_line
			(start -0.12065 -0.2794)
			(end 0.12065 -0.2794)
			(stroke
				(width 0.1)
				(type default)
			)
			(layer "F.Fab")
		)
		(fp_line
			(start -0.12065 -0.305054)
			(end -0.12065 -0.2794)
			(stroke
				(width 0.1)
				(type default)
			)
			(layer "F.Fab")
		)
		(fp_line
			(start -0.67945 0.3048)
			(end -0.67945 -0.305054)
			(stroke
				(width 0.1)
				(type default)
			)
			(layer "F.Fab")
		)
		(fp_line
			(start -0.67945 -0.305054)
			(end -0.12065 -0.305054)
			(stroke
				(width 0.1)
				(type default)
			)
			(layer "F.Fab")
		)
		(pad "1" smd circle
			(at -0.40005 0 180)
			(size 0 0)
			(layers "F.Cu" "F.Mask" "F.Paste")
			(net "PWRGD_P12V_SSD12_D")
		)
		(pad "2" smd circle
			(at 0.40005 0 180)
			(size 0 0)
			(layers "F.Cu" "F.Mask" "F.Paste")
			(net "PWRGD_P12V_SSD12_R")
		)
	)
)
